(kicad_pcb
	(version 20260206)
	(generator "pcbnew")
	(generator_version "10.0")
	(general
		(thickness 1.6)
		(legacy_teardrops no)
	)
	(paper "A4")
	(title_block
		(title "Bryce Canyon_IOM_M2_16342-2_OCP.brd")
		(comment 1 "Bryce Canyon / footprints 962-969 of 1146")
	)
	(layers
		(0 "F.Cu" signal "TOP")
		(4 "In1.Cu" signal "L2GND")
		(6 "In2.Cu" signal "L3")
		(8 "In3.Cu" signal "L4VCC")
		(10 "In4.Cu" signal "L5VCC")
		(12 "In5.Cu" signal "L6")
		(14 "In6.Cu" signal "L7GND")
		(2 "B.Cu" signal "BOTTOM")
		(9 "F.Adhes" user "F.Adhesive")
		(11 "B.Adhes" user "B.Adhesive")
		(13 "F.Paste" user "Package Geometry/Pastemask Top")
		(15 "B.Paste" user "Package Geometry/Pastemask Bottom")
		(5 "F.SilkS" user "Ref Des/Silkscreen Top")
		(7 "B.SilkS" user "Ref Des/Silkscreen Bottom")
		(1 "F.Mask" user "Board Geometry/Soldermask Top")
		(3 "B.Mask" user "Board Geometry/Soldermask Bottom")
		(17 "Dwgs.User" user "User.Drawings")
		(19 "Cmts.User" user "User.Comments")
		(21 "Eco1.User" user "User.Eco1")
		(23 "Eco2.User" user "User.Eco2")
		(25 "Edge.Cuts" user "Board Geometry/Outline")
		(27 "Margin" user)
		(31 "F.CrtYd" user "Package Geometry/Place Bound Top")
		(29 "B.CrtYd" user "Package Geometry/Place Bound Bottom")
		(35 "F.Fab" user "Ref Des/Assembly Top")
		(33 "B.Fab" user "Ref Des/Assembly Bottom")
	)
	(footprint ""
		(layer "B.Cu")
		(at 53.975 -154.9908 180)
		(property "Reference" "R315"
			(at 0 0 0)
			(layer "B.SilkS")
			(hide yes)
			(effects
				(font
					(size 1.27 1.27)
				)
				(justify mirror)
			)
		)
		(property "Value" "10KR2F-2-GP"
			(at -0.064008 -3.993896 180)
			(unlocked yes)
			(layer "B.Fab")
			(hide yes)
			(effects
				(font
					(size 1.016 1.016)
					(thickness 0.1524)
				)
				(justify mirror)
			)
		)
		(property "Device Type" "R402H16"
			(at -0.064008 -5.517896 180)
			(unlocked yes)
			(layer "B.Fab")
			(hide yes)
			(effects
				(font
					(size 1.016 1.016)
					(thickness 0.1524)
				)
				(justify mirror)
			)
		)
		(duplicate_pad_numbers_are_jumpers no)
		(fp_line
			(start 0.508 -0.9398)
			(end 0.508 0.9398)
			(stroke
				(width 0.1524)
				(type default)
			)
			(layer "B.SilkS")
		)
		(fp_line
			(start -0.508 -0.9398)
			(end 0.508 -0.9398)
			(stroke
				(width 0.1524)
				(type default)
			)
			(layer "B.SilkS")
		)
		(fp_rect
			(start 0.508 0.9398)
			(end -0.508 -0.9398)
			(stroke
				(width 0)
				(type default)
			)
			(fill no)
			(layer "B.CrtYd")
		)
		(fp_rect
			(start 0.508 0.9398)
			(end -0.508 -0.9398)
			(stroke
				(width 0)
				(type default)
			)
			(fill no)
			(layer "B.Fab")
		)
		(pad "1" smd custom
			(at 0 -0.4445)
			(size 0.1397 0.1397)
			(layers "B.Cu" "B.Mask" "B.Paste")
			(net "BMC_ENTEST")
			(options
				(clearance outline)
				(anchor circle)
			)
			(primitives
				(gr_poly
					(pts
						(arc
							(start -0.1778 0.2794)
							(mid -0.249642 0.249642)
							(end -0.2794 0.1778)
						)
						(arc
							(start -0.2794 -0.1778)
							(mid -0.249642 -0.249642)
							(end -0.1778 -0.2794)
						)
						(arc
							(start 0.1778 -0.2794)
							(mid 0.249642 -0.249642)
							(end 0.2794 -0.1778)
						)
						(arc
							(start 0.2794 0.1778)
							(mid 0.249642 0.249642)
							(end 0.1778 0.2794)
						)
					)
					(width 0)
					(fill yes)
				)
			)
		)
		(pad "2" smd custom
			(at 0 0.4445)
			(size 0.1397 0.1397)
			(layers "B.Cu" "B.Mask" "B.Paste")
			(net "GND")
			(options
				(clearance outline)
				(anchor circle)
			)
			(primitives
				(gr_poly
					(pts
						(arc
							(start -0.1778 0.2794)
							(mid -0.249642 0.249642)
							(end -0.2794 0.1778)
						)
						(arc
							(start -0.2794 -0.1778)
							(mid -0.249642 -0.249642)
							(end -0.1778 -0.2794)
						)
						(arc
							(start 0.1778 -0.2794)
							(mid 0.249642 -0.249642)
							(end 0.2794 -0.1778)
						)
						(arc
							(start 0.2794 0.1778)
							(mid 0.249642 0.249642)
							(end 0.1778 0.2794)
						)
					)
					(width 0)
					(fill yes)
				)
			)
		)
	)
	(footprint ""
		(layer "B.Cu")
		(at 55.626 -156.845)
		(property "Reference" "TP218"
			(at 0 0 0)
			(layer "B.SilkS")
			(hide yes)
			(effects
				(font
					(size 1.27 1.27)
				)
				(justify mirror)
			)
		)
		(property "Value" "TPAD28-2-GP"
			(at 0.0127 -1.6637 0)
			(unlocked yes)
			(layer "B.Fab")
			(hide yes)
			(effects
				(font
					(size 1.016 1.016)
					(thickness 0.1524)
				)
				(justify mirror)
			)
		)
		(property "Device Type" "TPAD28"
			(at 0.0127 -3.1877 0)
			(unlocked yes)
			(layer "B.Fab")
			(hide yes)
			(effects
				(font
					(size 1.016 1.016)
					(thickness 0.1524)
				)
				(justify mirror)
			)
		)
		(duplicate_pad_numbers_are_jumpers no)
		(fp_poly
			(pts
				(arc
					(start 0.3556 0)
					(mid -0.3556 0)
					(end 0.3556 0)
				)
			)
			(stroke
				(width 0)
				(type default)
			)
			(fill no)
			(layer "B.CrtYd")
		)
		(fp_poly
			(pts
				(arc
					(start 0.6096 0)
					(mid -0.6096 0)
					(end 0.6096 0)
				)
			)
			(stroke
				(width 0)
				(type default)
			)
			(fill no)
			(layer "B.Fab")
		)
		(pad "1" smd circle
			(at 0 0 180)
			(size 0.7112 0.7112)
			(layers "B.Cu" "B.Mask" "B.Paste")
			(net "ADC_P1V8")
		)
	)
	(footprint ""
		(layer "B.Cu")
		(at 206.547974 -102.391718 -90)
		(property "Reference" "R833"
			(at 0 0 90)
			(layer "B.SilkS")
			(hide yes)
			(effects
				(font
					(size 1.27 1.27)
				)
				(justify mirror)
			)
		)
		(property "Value" "200KR2F-L-GP"
			(at -0.064008 -3.993896 270)
			(unlocked yes)
			(layer "B.Fab")
			(hide yes)
			(effects
				(font
					(size 1.016 1.016)
					(thickness 0.1524)
				)
				(justify mirror)
			)
		)
		(property "Device Type" "R402H16"
			(at -0.064008 -5.517896 270)
			(unlocked yes)
			(layer "B.Fab")
			(hide yes)
			(effects
				(font
					(size 1.016 1.016)
					(thickness 0.1524)
				)
				(justify mirror)
			)
		)
		(duplicate_pad_numbers_are_jumpers no)
		(fp_line
			(start -0.508 -0.9398)
			(end 0.508 -0.9398)
			(stroke
				(width 0.1524)
				(type default)
			)
			(layer "B.SilkS")
		)
		(fp_line
			(start 0.508 -0.9398)
			(end 0.508 0.9398)
			(stroke
				(width 0.1524)
				(type default)
			)
			(layer "B.SilkS")
		)
		(fp_rect
			(start 0.508 0.9398)
			(end -0.508 -0.9398)
			(stroke
				(width 0)
				(type default)
			)
			(fill no)
			(layer "B.CrtYd")
		)
		(fp_rect
			(start 0.508 0.9398)
			(end -0.508 -0.9398)
			(stroke
				(width 0)
				(type default)
			)
			(fill no)
			(layer "B.Fab")
		)
		(pad "1" smd custom
			(at 0 -0.4445 90)
			(size 0.1397 0.1397)
			(layers "B.Cu" "B.Mask" "B.Paste")
			(net "U82_VREF2")
			(options
				(clearance outline)
				(anchor circle)
			)
			(primitives
				(gr_poly
					(pts
						(arc
							(start -0.1778 0.2794)
							(mid -0.249642 0.249642)
							(end -0.2794 0.1778)
						)
						(arc
							(start -0.2794 -0.1778)
							(mid -0.249642 -0.249642)
							(end -0.1778 -0.2794)
						)
						(arc
							(start 0.1778 -0.2794)
							(mid 0.249642 -0.249642)
							(end 0.2794 -0.1778)
						)
						(arc
							(start 0.2794 0.1778)
							(mid 0.249642 0.249642)
							(end 0.1778 0.2794)
						)
					)
					(width 0)
					(fill yes)
				)
			)
		)
		(pad "2" smd custom
			(at 0 0.4445 90)
			(size 0.1397 0.1397)
			(layers "B.Cu" "B.Mask" "B.Paste")
			(net "P3V3_STBY")
			(options
				(clearance outline)
				(anchor circle)
			)
			(primitives
				(gr_poly
					(pts
						(arc
							(start -0.1778 0.2794)
							(mid -0.249642 0.249642)
							(end -0.2794 0.1778)
						)
						(arc
							(start -0.2794 -0.1778)
							(mid -0.249642 -0.249642)
							(end -0.1778 -0.2794)
						)
						(arc
							(start 0.1778 -0.2794)
							(mid 0.249642 -0.249642)
							(end 0.2794 -0.1778)
						)
						(arc
							(start 0.2794 0.1778)
							(mid 0.249642 0.249642)
							(end 0.1778 0.2794)
						)
					)
					(width 0)
					(fill yes)
				)
			)
		)
	)
	(footprint ""
		(layer "B.Cu")
		(at 38.98773 -140.300964 180)
		(property "Reference" "C97"
			(at 0 0 0)
			(layer "B.SilkS")
			(hide yes)
			(effects
				(font
					(size 1.27 1.27)
				)
				(justify mirror)
			)
		)
		(property "Value" "SC1U16V3KX-5GP"
			(at 0 -2.8194 180)
			(unlocked yes)
			(layer "B.Fab")
			(hide yes)
			(effects
				(font
					(size 1.016 1.016)
					(thickness 0.1524)
				)
				(justify mirror)
			)
		)
		(property "Device Type" "C603H36"
			(at 0 -4.3434 180)
			(unlocked yes)
			(layer "B.Fab")
			(hide yes)
			(effects
				(font
					(size 1.016 1.016)
					(thickness 0.1524)
				)
				(justify mirror)
			)
		)
		(duplicate_pad_numbers_are_jumpers no)
		(fp_line
			(start -0.508 0)
			(end 0.508 0)
			(stroke
				(width 0.2032)
				(type default)
			)
			(layer "B.SilkS")
		)
		(fp_rect
			(start 0.5842 1.3335)
			(end -0.5842 -1.3335)
			(stroke
				(width 0)
				(type default)
			)
			(fill no)
			(layer "B.CrtYd")
		)
		(fp_rect
			(start 0.5842 1.3335)
			(end -0.5842 -1.3335)
			(stroke
				(width 0)
				(type default)
			)
			(fill no)
			(layer "B.Fab")
		)
		(pad "1" smd custom
			(at 0 -0.762)
			(size 0.2159 0.2159)
			(layers "B.Cu" "B.Mask" "B.Paste")
			(net "P3V3_STBY")
			(options
				(clearance outline)
				(anchor circle)
			)
			(primitives
				(gr_poly
					(pts
						(arc
							(start -0.3302 0.4318)
							(mid -0.402042 0.402042)
							(end -0.4318 0.3302)
						)
						(arc
							(start -0.4318 -0.3302)
							(mid -0.402042 -0.402042)
							(end -0.3302 -0.4318)
						)
						(arc
							(start 0.3302 -0.4318)
							(mid 0.402042 -0.402042)
							(end 0.4318 -0.3302)
						)
						(arc
							(start 0.4318 0.3302)
							(mid 0.402042 0.402042)
							(end 0.3302 0.4318)
						)
					)
					(width 0)
					(fill yes)
				)
			)
		)
		(pad "2" smd custom
			(at 0 0.762)
			(size 0.2159 0.2159)
			(layers "B.Cu" "B.Mask" "B.Paste")
			(net "GND")
			(options
				(clearance outline)
				(anchor circle)
			)
			(primitives
				(gr_poly
					(pts
						(arc
							(start -0.3302 0.4318)
							(mid -0.402042 0.402042)
							(end -0.4318 0.3302)
						)
						(arc
							(start -0.4318 -0.3302)
							(mid -0.402042 -0.402042)
							(end -0.3302 -0.4318)
						)
						(arc
							(start 0.3302 -0.4318)
							(mid 0.402042 -0.402042)
							(end 0.4318 -0.3302)
						)
						(arc
							(start 0.4318 0.3302)
							(mid 0.402042 0.402042)
							(end 0.3302 0.4318)
						)
					)
					(width 0)
					(fill yes)
				)
			)
		)
	)
	(footprint ""
		(layer "B.Cu")
		(at 56.007 -141.6812)
		(property "Reference" "TP73"
			(at 0 0 0)
			(layer "B.SilkS")
			(hide yes)
			(effects
				(font
					(size 1.27 1.27)
				)
				(justify mirror)
			)
		)
		(property "Value" "TPAD28-2-GP"
			(at 0.0127 -1.6637 0)
			(unlocked yes)
			(layer "B.Fab")
			(hide yes)
			(effects
				(font
					(size 1.016 1.016)
					(thickness 0.1524)
				)
				(justify mirror)
			)
		)
		(property "Device Type" "TPAD28"
			(at 0.0127 -3.1877 0)
			(unlocked yes)
			(layer "B.Fab")
			(hide yes)
			(effects
				(font
					(size 1.016 1.016)
					(thickness 0.1524)
				)
				(justify mirror)
			)
		)
		(duplicate_pad_numbers_are_jumpers no)
		(fp_poly
			(pts
				(arc
					(start 0.3556 0)
					(mid -0.3556 0)
					(end 0.3556 0)
				)
			)
			(stroke
				(width 0)
				(type default)
			)
			(fill no)
			(layer "B.CrtYd")
		)
		(fp_poly
			(pts
				(arc
					(start 0.6096 0)
					(mid -0.6096 0)
					(end 0.6096 0)
				)
			)
			(stroke
				(width 0)
				(type default)
			)
			(fill no)
			(layer "B.Fab")
		)
		(pad "1" smd circle
			(at 0 0 180)
			(size 0.7112 0.7112)
			(layers "B.Cu" "B.Mask" "B.Paste")
			(net "TP_BMC_GPIOI5")
		)
	)
	(footprint ""
		(layer "B.Cu")
		(at 201.845418 -130.391408 180)
		(property "Reference" "C629"
			(at 0 0 0)
			(layer "B.SilkS")
			(hide yes)
			(effects
				(font
					(size 1.27 1.27)
				)
				(justify mirror)
			)
		)
		(property "Value" "SCD1U16V2KX-3GP"
			(at -1.1811 -2.7051 180)
			(unlocked yes)
			(layer "B.Fab")
			(hide yes)
			(effects
				(font
					(size 1.016 1.016)
					(thickness 0.1524)
				)
				(justify mirror)
			)
		)
		(property "Device Type" "C402H22"
			(at -1.1811 -4.2291 180)
			(unlocked yes)
			(layer "B.Fab")
			(hide yes)
			(effects
				(font
					(size 1.016 1.016)
					(thickness 0.1524)
				)
				(justify mirror)
			)
		)
		(duplicate_pad_numbers_are_jumpers no)
		(fp_rect
			(start 0.4318 0.9525)
			(end -0.4318 -0.9525)
			(stroke
				(width 0)
				(type default)
			)
			(fill no)
			(layer "B.CrtYd")
		)
		(fp_rect
			(start 0.4318 0.9525)
			(end -0.4318 -0.9525)
			(stroke
				(width 0)
				(type default)
			)
			(fill no)
			(layer "B.Fab")
		)
		(pad "1" smd custom
			(at 0 -0.4445)
			(size 0.1524 0.1524)
			(layers "B.Cu" "B.Mask" "B.Paste")
			(net "P3V3_M2")
			(options
				(clearance outline)
				(anchor circle)
			)
			(primitives
				(gr_poly
					(pts
						(arc
							(start 0.3048 0.2032)
							(mid 0.275042 0.275042)
							(end 0.2032 0.3048)
						)
						(arc
							(start -0.2032 0.3048)
							(mid -0.275042 0.275042)
							(end -0.3048 0.2032)
						)
						(arc
							(start -0.3048 -0.2032)
							(mid -0.275042 -0.275042)
							(end -0.2032 -0.3048)
						)
						(arc
							(start 0.2032 -0.3048)
							(mid 0.275042 -0.275042)
							(end 0.3048 -0.2032)
						)
					)
					(width 0)
					(fill yes)
				)
			)
		)
		(pad "2" smd custom
			(at 0 0.4445)
			(size 0.1524 0.1524)
			(layers "B.Cu" "B.Mask" "B.Paste")
			(net "GND")
			(options
				(clearance outline)
				(anchor circle)
			)
			(primitives
				(gr_poly
					(pts
						(arc
							(start 0.3048 0.2032)
							(mid 0.275042 0.275042)
							(end 0.2032 0.3048)
						)
						(arc
							(start -0.2032 0.3048)
							(mid -0.275042 0.275042)
							(end -0.3048 0.2032)
						)
						(arc
							(start -0.3048 -0.2032)
							(mid -0.275042 -0.275042)
							(end -0.2032 -0.3048)
						)
						(arc
							(start 0.2032 -0.3048)
							(mid 0.275042 -0.275042)
							(end 0.3048 -0.2032)
						)
					)
					(width 0)
					(fill yes)
				)
			)
		)
	)
	(footprint ""
		(layer "B.Cu")
		(at 207.059784 -108.793534 90)
		(property "Reference" "R813"
			(at 0 0 90)
			(layer "B.SilkS")
			(hide yes)
			(effects
				(font
					(size 1.27 1.27)
				)
				(justify mirror)
			)
		)
		(property "Value" "1KR2F-3-GP"
			(at -0.064008 -3.993896 90)
			(unlocked yes)
			(layer "B.Fab")
			(hide yes)
			(effects
				(font
					(size 1.016 1.016)
					(thickness 0.1524)
				)
				(justify mirror)
			)
		)
		(property "Device Type" "R402H16"
			(at -0.064008 -5.517896 90)
			(unlocked yes)
			(layer "B.Fab")
			(hide yes)
			(effects
				(font
					(size 1.016 1.016)
					(thickness 0.1524)
				)
				(justify mirror)
			)
		)
		(duplicate_pad_numbers_are_jumpers no)
		(fp_line
			(start 0.508 -0.9398)
			(end 0.508 0.9398)
			(stroke
				(width 0.1524)
				(type default)
			)
			(layer "B.SilkS")
		)
		(fp_line
			(start -0.508 -0.9398)
			(end 0.508 -0.9398)
			(stroke
				(width 0.1524)
				(type default)
			)
			(layer "B.SilkS")
		)
		(fp_rect
			(start 0.508 0.9398)
			(end -0.508 -0.9398)
			(stroke
				(width 0)
				(type default)
			)
			(fill no)
			(layer "B.CrtYd")
		)
		(fp_rect
			(start 0.508 0.9398)
			(end -0.508 -0.9398)
			(stroke
				(width 0)
				(type default)
			)
			(fill no)
			(layer "B.Fab")
		)
		(pad "1" smd custom
			(at 0 -0.4445 270)
			(size 0.1397 0.1397)
			(layers "B.Cu" "B.Mask" "B.Paste")
			(net "P1V8_STBY")
			(options
				(clearance outline)
				(anchor circle)
			)
			(primitives
				(gr_poly
					(pts
						(arc
							(start -0.1778 0.2794)
							(mid -0.249642 0.249642)
							(end -0.2794 0.1778)
						)
						(arc
							(start -0.2794 -0.1778)
							(mid -0.249642 -0.249642)
							(end -0.1778 -0.2794)
						)
						(arc
							(start 0.1778 -0.2794)
							(mid 0.249642 -0.249642)
							(end 0.2794 -0.1778)
						)
						(arc
							(start 0.2794 0.1778)
							(mid 0.249642 0.249642)
							(end 0.1778 0.2794)
						)
					)
					(width 0)
					(fill yes)
				)
			)
		)
		(pad "2" smd custom
			(at 0 0.4445 270)
			(size 0.1397 0.1397)
			(layers "B.Cu" "B.Mask" "B.Paste")
			(net "I2C_M2_1_1V8_SCL")
			(options
				(clearance outline)
				(anchor circle)
			)
			(primitives
				(gr_poly
					(pts
						(arc
							(start -0.1778 0.2794)
							(mid -0.249642 0.249642)
							(end -0.2794 0.1778)
						)
						(arc
							(start -0.2794 -0.1778)
							(mid -0.249642 -0.249642)
							(end -0.1778 -0.2794)
						)
						(arc
							(start 0.1778 -0.2794)
							(mid 0.249642 -0.249642)
							(end 0.2794 -0.1778)
						)
						(arc
							(start 0.2794 0.1778)
							(mid 0.249642 0.249642)
							(end 0.1778 0.2794)
						)
					)
					(width 0)
					(fill yes)
				)
			)
		)
	)
	(footprint ""
		(layer "B.Cu")
		(at 68.530724 -144.691608)
		(property "Reference" "R161"
			(at 0 0 0)
			(layer "B.SilkS")
			(hide yes)
			(effects
				(font
					(size 1.27 1.27)
				)
				(justify mirror)
			)
		)
		(property "Value" "0R2J-2-GP"
			(at -0.064008 -3.993896 0)
			(unlocked yes)
			(layer "B.Fab")
			(hide yes)
			(effects
				(font
					(size 1.016 1.016)
					(thickness 0.1524)
				)
				(justify mirror)
			)
		)
		(property "Device Type" "R402H16"
			(at -0.064008 -5.517896 0)
			(unlocked yes)
			(layer "B.Fab")
			(hide yes)
			(effects
				(font
					(size 1.016 1.016)
					(thickness 0.1524)
				)
				(justify mirror)
			)
		)
		(duplicate_pad_numbers_are_jumpers no)
		(fp_line
			(start -0.508 -0.9398)
			(end 0.508 -0.9398)
			(stroke
				(width 0.1524)
				(type default)
			)
			(layer "B.SilkS")
		)
		(fp_line
			(start 0.508 -0.9398)
			(end 0.508 0.9398)
			(stroke
				(width 0.1524)
				(type default)
			)
			(layer "B.SilkS")
		)
		(fp_rect
			(start 0.508 0.9398)
			(end -0.508 -0.9398)
			(stroke
				(width 0)
				(type default)
			)
			(fill no)
			(layer "B.CrtYd")
		)
		(fp_rect
			(start 0.508 0.9398)
			(end -0.508 -0.9398)
			(stroke
				(width 0)
				(type default)
			)
			(fill no)
			(layer "B.Fab")
		)
		(pad "1" smd custom
			(at 0 -0.4445 180)
			(size 0.1397 0.1397)
			(layers "B.Cu" "B.Mask" "B.Paste")
			(net "BMC_SMB12_DAT")
			(options
				(clearance outline)
				(anchor circle)
			)
			(primitives
				(gr_poly
					(pts
						(arc
							(start -0.1778 0.2794)
							(mid -0.249642 0.249642)
							(end -0.2794 0.1778)
						)
						(arc
							(start -0.2794 -0.1778)
							(mid -0.249642 -0.249642)
							(end -0.1778 -0.2794)
						)
						(arc
							(start 0.1778 -0.2794)
							(mid 0.249642 -0.249642)
							(end 0.2794 -0.1778)
						)
						(arc
							(start 0.2794 0.1778)
							(mid 0.249642 0.249642)
							(end 0.1778 0.2794)
						)
					)
					(width 0)
					(fill yes)
				)
			)
		)
		(pad "2" smd custom
			(at 0 0.4445 180)
			(size 0.1397 0.1397)
			(layers "B.Cu" "B.Mask" "B.Paste")
			(net "I2C_DEBUG_SDA_L")
			(options
				(clearance outline)
				(anchor circle)
			)
			(primitives
				(gr_poly
					(pts
						(arc
							(start -0.1778 0.2794)
							(mid -0.249642 0.249642)
							(end -0.2794 0.1778)
						)
						(arc
							(start -0.2794 -0.1778)
							(mid -0.249642 -0.249642)
							(end -0.1778 -0.2794)
						)
						(arc
							(start 0.1778 -0.2794)
							(mid 0.249642 -0.249642)
							(end 0.2794 -0.1778)
						)
						(arc
							(start 0.2794 0.1778)
							(mid 0.249642 0.249642)
							(end 0.1778 0.2794)
						)
					)
					(width 0)
					(fill yes)
				)
			)
		)
	)
)
